# BASEBOARD_FAB2 (Tioga Pass) — schematic netlist excerpt (pin names and nets, part order shuffled) for the footprints in the layout excerpt that follows; sources: Cadence DE-HDL packaged netlist, KiCad conversion of Wiwynn_Tioga_Pass_MB.brd

R8G7  RES  0.0 5% CHIP  pkg 0402  page 189 : A = JTAG_PLD_TDI ; B = JTAG_PLD_TDI_MUX
CF6  SC22P50V2JN-4GP  5%  pkg SMD-BCG  page 201 : \1\ = VR_PVSA_CPU0_BIREF1 ; \2\ = ISENSE_PVSA_CPU0_IMON
C5D45  CAP_A  22.0UF 4V 20% X6S  pkg 0603V  page 42 : A = PVCCIN_CPU0 ; B = GND

(kicad_pcb
	(version 20260206)
	(generator "pcbnew")
	(generator_version "10.0")
	(general
		(thickness 1.6)
		(legacy_teardrops no)
	)
	(paper "A4")
	(title_block
		(title "Wiwynn_Tioga_Pass_MB.brd")
		(comment 1 "Tioga Pass / footprints 61-63 of 4770")
	)
	(layers
		(0 "F.Cu" signal "TOP")
		(4 "In1.Cu" signal "L2GND")
		(6 "In2.Cu" signal "L3")
		(8 "In3.Cu" signal "L4GND")
		(10 "In4.Cu" signal "L5")
		(12 "In5.Cu" signal "L6GND")
		(14 "In6.Cu" signal "L7VCC")
		(16 "In7.Cu" signal "L8VCC")
		(18 "In8.Cu" signal "L9GND")
		(20 "In9.Cu" signal "L10")
		(22 "In10.Cu" signal "L11GND")
		(24 "In11.Cu" signal "L12")
		(26 "In12.Cu" signal "L13GND")
		(2 "B.Cu" signal "BOTTOM")
		(9 "F.Adhes" user "F.Adhesive")
		(11 "B.Adhes" user "B.Adhesive")
		(13 "F.Paste" user "Package Geometry/Pastemask Top")
		(15 "B.Paste" user "Package Geometry/Pastemask Bottom")
		(5 "F.SilkS" user "Ref Des/Silkscreen Top")
		(7 "B.SilkS" user "Ref Des/Silkscreen Bottom")
		(1 "F.Mask" user "Board Geometry/Soldermask Top")
		(3 "B.Mask" user "Board Geometry/Soldermask Bottom")
		(17 "Dwgs.User" user "User.Drawings")
		(19 "Cmts.User" user "User.Comments")
		(21 "Eco1.User" user "User.Eco1")
		(23 "Eco2.User" user "User.Eco2")
		(25 "Edge.Cuts" user "Board Geometry/Outline")
		(27 "Margin" user)
		(31 "F.CrtYd" user "Package Geometry/Place Bound Top")
		(29 "B.CrtYd" user "Package Geometry/Place Bound Bottom")
		(35 "F.Fab" user "Ref Des/Assembly Top")
		(33 "B.Fab" user "Ref Des/Assembly Bottom")
	)
	(footprint ""
		(layer "F.Cu")
		(at 403.606 4.0894 90)
		(property "Reference" "R8G7"
			(at 0 0 90)
			(layer "F.SilkS")
			(hide yes)
			(effects
				(font
					(size 1.27 1.27)
				)
			)
		)
		(property "Value" ""
			(at 0 0 90)
			(layer "F.Fab")
			(effects
				(font
					(size 1.27 1.27)
				)
			)
		)
		(duplicate_pad_numbers_are_jumpers no)
		(fp_poly
			(pts
				(xy -0.2794 -0.1016) (xy 0.2794 -0.1016) (xy 0.2794 0.9906) (xy -0.2794 0.9906)
			)
			(stroke
				(width 0)
				(type default)
			)
			(fill no)
			(layer "F.CrtYd")
		)
		(fp_line
			(start 0.2794 -0.1016)
			(end -0.2794 -0.1016)
			(stroke
				(width 0.1)
				(type default)
			)
			(layer "F.Fab")
		)
		(fp_line
			(start -0.2794 -0.1016)
			(end -0.2794 0.9906)
			(stroke
				(width 0.1)
				(type default)
			)
			(layer "F.Fab")
		)
		(fp_line
			(start 0.2794 0.9906)
			(end 0.2794 -0.1016)
			(stroke
				(width 0.1)
				(type default)
			)
			(layer "F.Fab")
		)
		(fp_line
			(start -0.2794 0.9906)
			(end 0.2794 0.9906)
			(stroke
				(width 0.1)
				(type default)
			)
			(layer "F.Fab")
		)
		(pad "1" smd rect
			(at 0 0 90)
			(size 0.508 0.508)
			(layers "F.Cu" "F.Mask" "F.Paste")
			(net "JTAG_PLD_TDI")
		)
		(pad "2" smd rect
			(at 0 0.889 90)
			(size 0.508 0.508)
			(layers "F.Cu" "F.Mask" "F.Paste")
			(net "JTAG_PLD_TDI_MUX")
		)
		(zone
			(layer "F.Cu")
			(hatch none 0.5)
			(connect_pads
				(clearance 0)
			)
			(min_thickness 0.25)
			(keepout
				(tracks allowed)
				(vias not_allowed)
				(pads allowed)
				(copperpour not_allowed)
				(footprints allowed)
			)
			(placement
				(enabled no)
				(sheetname "")
			)
			(fill
				(thermal_gap 0.5)
				(thermal_bridge_width 0.5)
				(island_removal_mode 0)
			)
			(polygon
				(pts
					(xy 403.86 4.3434) (xy 403.86 3.8354) (xy 404.241 3.8354) (xy 404.241 4.3434)
				)
			)
		)
		(zone
			(layer "F.Cu")
			(hatch none 0.5)
			(connect_pads
				(clearance 0)
			)
			(min_thickness 0.25)
			(keepout
				(tracks not_allowed)
				(vias allowed)
				(pads allowed)
				(copperpour not_allowed)
				(footprints allowed)
			)
			(placement
				(enabled no)
				(sheetname "")
			)
			(fill
				(thermal_gap 0.5)
				(thermal_bridge_width 0.5)
				(island_removal_mode 0)
			)
			(polygon
				(pts
					(xy 404.241 4.3434) (xy 404.241 3.8354) (xy 403.86 3.8354) (xy 403.86 4.3434)
				)
			)
		)
	)
	(footprint ""
		(layer "F.Cu")
		(at 187.833 -75.057 -90)
		(property "Reference" "CF6"
			(at 0 0 270)
			(layer "F.SilkS")
			(hide yes)
			(effects
				(font
					(size 1.27 1.27)
				)
			)
		)
		(property "Value" "*"
			(at 1.1811 -2.8194 270)
			(unlocked yes)
			(layer "F.Fab")
			(hide yes)
			(effects
				(font
					(size 1.27 1.016)
					(thickness 0.1524)
				)
			)
		)
		(property "Device Type" "SC22P50V2JN-4GP_SMD-BCG-SC22P5A"
			(at 1.1811 -4.3434 270)
			(unlocked yes)
			(layer "F.Fab")
			(hide yes)
			(effects
				(font
					(size 1.27 1.016)
					(thickness 0.1524)
				)
			)
		)
		(duplicate_pad_numbers_are_jumpers no)
		(fp_rect
			(start -0.4318 0.9525)
			(end 0.4318 -0.9525)
			(stroke
				(width 0)
				(type default)
			)
			(fill no)
			(layer "F.CrtYd")
		)
		(fp_rect
			(start -0.4318 0.9525)
			(end 0.4318 -0.9525)
			(stroke
				(width 0)
				(type default)
			)
			(fill no)
			(layer "F.Fab")
		)
		(pad "1" smd custom
			(at 0 -0.4445 270)
			(size 0.1524 0.1524)
			(layers "F.Cu" "F.Mask" "F.Paste")
			(net "VR_PVSA_CPU0_BIREF1")
			(options
				(clearance outline)
				(anchor circle)
			)
			(primitives
				(gr_poly
					(pts
						(arc
							(start 0.3048 -0.2032)
							(mid 0.275042 -0.275042)
							(end 0.2032 -0.3048)
						)
						(arc
							(start -0.2032 -0.3048)
							(mid -0.275042 -0.275042)
							(end -0.3048 -0.2032)
						)
						(arc
							(start -0.3048 0.2032)
							(mid -0.275042 0.275042)
							(end -0.2032 0.3048)
						)
						(arc
							(start 0.2032 0.3048)
							(mid 0.275042 0.275042)
							(end 0.3048 0.2032)
						)
					)
					(width 0)
					(fill yes)
				)
			)
		)
		(pad "2" smd custom
			(at 0 0.4445 270)
			(size 0.1524 0.1524)
			(layers "F.Cu" "F.Mask" "F.Paste")
			(net "ISENSE_PVSA_CPU0_IMON")
			(options
				(clearance outline)
				(anchor circle)
			)
			(primitives
				(gr_poly
					(pts
						(arc
							(start 0.3048 -0.2032)
							(mid 0.275042 -0.275042)
							(end 0.2032 -0.3048)
						)
						(arc
							(start -0.2032 -0.3048)
							(mid -0.275042 -0.275042)
							(end -0.3048 -0.2032)
						)
						(arc
							(start -0.3048 0.2032)
							(mid -0.275042 0.275042)
							(end -0.2032 0.3048)
						)
						(arc
							(start 0.2032 0.3048)
							(mid 0.275042 0.275042)
							(end 0.3048 0.2032)
						)
					)
					(width 0)
					(fill yes)
				)
			)
		)
	)
	(footprint ""
		(layer "F.Cu")
		(at 265.675872 -73.318116)
		(property "Reference" "C5D45"
			(at 0 0 0)
			(layer "F.SilkS")
			(hide yes)
			(effects
				(font
					(size 1.27 1.27)
				)
			)
		)
		(property "Value" ""
			(at 0 0 0)
			(layer "F.Fab")
			(effects
				(font
					(size 1.27 1.27)
				)
			)
		)
		(duplicate_pad_numbers_are_jumpers no)
		(fp_poly
			(pts
				(xy -0.4953 -0.2032) (xy 0.4953 -0.2032) (xy 0.4953 1.6002) (xy -0.4953 1.6002)
			)
			(stroke
				(width 0)
				(type default)
			)
			(fill no)
			(layer "F.CrtYd")
		)
		(fp_line
			(start -0.4953 -0.2032)
			(end 0.4953 -0.2032)
			(stroke
				(width 0.1)
				(type default)
			)
			(layer "F.Fab")
		)
		(fp_line
			(start -0.4953 1.6002)
			(end -0.4953 -0.2032)
			(stroke
				(width 0.1)
				(type default)
			)
			(layer "F.Fab")
		)
		(fp_line
			(start 0.4953 -0.2032)
			(end 0.4953 1.6002)
			(stroke
				(width 0.1)
				(type default)
			)
			(layer "F.Fab")
		)
		(fp_line
			(start 0.4953 1.6002)
			(end -0.4953 1.6002)
			(stroke
				(width 0.1)
				(type default)
			)
			(layer "F.Fab")
		)
		(pad "1" smd rect
			(at 0 0)
			(size 0.762 0.889)
			(layers "F.Cu" "F.Mask" "F.Paste")
			(net "PVCCIN_CPU0")
		)
		(pad "2" smd rect
			(at 0 1.397)
			(size 0.762 0.889)
			(layers "F.Cu" "F.Mask" "F.Paste")
			(net "GND")
		)
		(zone
			(layer "F.Cu")
			(hatch none 0.5)
			(connect_pads
				(clearance 0)
			)
			(min_thickness 0.25)
			(keepout
				(tracks not_allowed)
				(vias allowed)
				(pads allowed)
				(copperpour not_allowed)
				(footprints allowed)
			)
			(placement
				(enabled no)
				(sheetname "")
			)
			(fill
				(thermal_gap 0.5)
				(thermal_bridge_width 0.5)
				(island_removal_mode 0)
			)
			(polygon
				(pts
					(xy 265.294872 -72.873616) (xy 266.056872 -72.873616) (xy 266.056872 -72.365616) (xy 265.294872 -72.365616)
				)
			)
		)
	)
)
